(kicad_pcb
	(version 20260206)
	(generator "pcbnew")
	(generator_version "10.0")
	(general
		(thickness 1.6)
		(legacy_teardrops no)
	)
	(paper "A4")
	(title_block
		(title "01162023_DA0F0TEBIF0_F0T_Expander_BD_F_brd_V02_OCP.brd")
		(comment 1 "Grand Teton / footprints 2302-2304 of 9728")
	)
	(layers
		(0 "F.Cu" signal "TOP")
		(4 "In1.Cu" signal "GND")
		(6 "In2.Cu" signal "VCC")
		(8 "In3.Cu" signal "VCC1")
		(10 "In4.Cu" signal "GND1")
		(12 "In5.Cu" signal "IN1")
		(14 "In6.Cu" signal "GND2")
		(16 "In7.Cu" signal "IN2")
		(18 "In8.Cu" signal "GND3")
		(20 "In9.Cu" signal "IN3")
		(22 "In10.Cu" signal "GND4")
		(24 "In11.Cu" signal "IN4")
		(26 "In12.Cu" signal "GND5")
		(28 "In13.Cu" signal "IN5")
		(30 "In14.Cu" signal "GND6")
		(32 "In15.Cu" signal "IN6")
		(34 "In16.Cu" signal "GND7")
		(2 "B.Cu" signal "BOTTOM")
		(9 "F.Adhes" user "F.Adhesive")
		(11 "B.Adhes" user "B.Adhesive")
		(13 "F.Paste" user "Package Geometry/Pastemask Top")
		(15 "B.Paste" user "Package Geometry/Pastemask Bottom")
		(5 "F.SilkS" user "Ref Des/Silkscreen Top")
		(7 "B.SilkS" user "Ref Des/Silkscreen Bottom")
		(1 "F.Mask" user "Board Geometry/Soldermask Top")
		(3 "B.Mask" user "Board Geometry/Soldermask Bottom")
		(17 "Dwgs.User" user "User.Drawings")
		(19 "Cmts.User" user "User.Comments")
		(21 "Eco1.User" user "User.Eco1")
		(23 "Eco2.User" user "User.Eco2")
		(25 "Edge.Cuts" user "Board Geometry/Outline")
		(27 "Margin" user)
		(31 "F.CrtYd" user "Package Geometry/Place Bound Top")
		(29 "B.CrtYd" user "Package Geometry/Place Bound Bottom")
		(35 "F.Fab" user "Ref Des/Assembly Top")
		(33 "B.Fab" user "Ref Des/Assembly Bottom")
	)
	(footprint ""
		(layer "F.Cu")
		(at 221.251272 -149.054312 180)
		(property "Reference" "R4192"
			(at 0 0 180)
			(layer "F.SilkS")
			(hide yes)
			(effects
				(font
					(size 1.27 1.27)
				)
			)
		)
		(property "Value" ""
			(at 0 0 180)
			(layer "F.Fab")
			(effects
				(font
					(size 1.27 1.27)
				)
			)
		)
		(duplicate_pad_numbers_are_jumpers no)
		(fp_line
			(start 0.7874 0.4064)
			(end -0.7874 0.4064)
			(stroke
				(width 0.1524)
				(type default)
			)
			(layer "F.SilkS")
		)
		(fp_line
			(start 0.7874 -0.4064)
			(end 0.7874 0.4064)
			(stroke
				(width 0.1524)
				(type default)
			)
			(layer "F.SilkS")
		)
		(fp_line
			(start -0.7874 0.4064)
			(end -0.7874 -0.4064)
			(stroke
				(width 0.1524)
				(type default)
			)
			(layer "F.SilkS")
		)
		(fp_line
			(start -0.7874 -0.4064)
			(end 0.7874 -0.4064)
			(stroke
				(width 0.1524)
				(type default)
			)
			(layer "F.SilkS")
		)
		(fp_line
			(start 0.67945 0.3048)
			(end 0.120396 0.3048)
			(stroke
				(width 0.1)
				(type default)
			)
			(layer "F.Fab")
		)
		(fp_line
			(start 0.67945 -0.3048)
			(end 0.67945 0.3048)
			(stroke
				(width 0.1)
				(type default)
			)
			(layer "F.Fab")
		)
		(fp_line
			(start 0.12065 -0.2794)
			(end 0.12065 -0.3048)
			(stroke
				(width 0.1)
				(type default)
			)
			(layer "F.Fab")
		)
		(fp_line
			(start 0.12065 -0.3048)
			(end 0.67945 -0.3048)
			(stroke
				(width 0.1)
				(type default)
			)
			(layer "F.Fab")
		)
		(fp_line
			(start 0.120396 0.3048)
			(end 0.120396 0.2794)
			(stroke
				(width 0.1)
				(type default)
			)
			(layer "F.Fab")
		)
		(fp_line
			(start 0.120396 0.2794)
			(end -0.12065 0.2794)
			(stroke
				(width 0.1)
				(type default)
			)
			(layer "F.Fab")
		)
		(fp_line
			(start -0.12065 0.3048)
			(end -0.67945 0.3048)
			(stroke
				(width 0.1)
				(type default)
			)
			(layer "F.Fab")
		)
		(fp_line
			(start -0.12065 0.2794)
			(end -0.12065 0.3048)
			(stroke
				(width 0.1)
				(type default)
			)
			(layer "F.Fab")
		)
		(fp_line
			(start -0.12065 -0.2794)
			(end 0.12065 -0.2794)
			(stroke
				(width 0.1)
				(type default)
			)
			(layer "F.Fab")
		)
		(fp_line
			(start -0.12065 -0.305054)
			(end -0.12065 -0.2794)
			(stroke
				(width 0.1)
				(type default)
			)
			(layer "F.Fab")
		)
		(fp_line
			(start -0.67945 0.3048)
			(end -0.67945 -0.305054)
			(stroke
				(width 0.1)
				(type default)
			)
			(layer "F.Fab")
		)
		(fp_line
			(start -0.67945 -0.305054)
			(end -0.12065 -0.305054)
			(stroke
				(width 0.1)
				(type default)
			)
			(layer "F.Fab")
		)
		(pad "1" smd circle
			(at -0.40005 0 180)
			(size 0 0)
			(layers "F.Cu" "F.Mask" "F.Paste")
			(net "FM_CK440_PEX_MXCK_25M_100M")
		)
		(pad "2" smd circle
			(at 0.40005 0 180)
			(size 0 0)
			(layers "F.Cu" "F.Mask" "F.Paste")
			(net "P3V3")
		)
	)
	(footprint ""
		(layer "F.Cu")
		(at 194.343782 -48.93691 180)
		(property "Reference" "R578"
			(at 0 0 180)
			(layer "F.SilkS")
			(hide yes)
			(effects
				(font
					(size 1.27 1.27)
				)
			)
		)
		(property "Value" ""
			(at 0 0 180)
			(layer "F.Fab")
			(effects
				(font
					(size 1.27 1.27)
				)
			)
		)
		(duplicate_pad_numbers_are_jumpers no)
		(fp_line
			(start 0.7874 0.4064)
			(end -0.7874 0.4064)
			(stroke
				(width 0.1524)
				(type default)
			)
			(layer "F.SilkS")
		)
		(fp_line
			(start 0.7874 -0.4064)
			(end 0.7874 0.4064)
			(stroke
				(width 0.1524)
				(type default)
			)
			(layer "F.SilkS")
		)
		(fp_line
			(start -0.7874 0.4064)
			(end -0.7874 -0.4064)
			(stroke
				(width 0.1524)
				(type default)
			)
			(layer "F.SilkS")
		)
		(fp_line
			(start -0.7874 -0.4064)
			(end 0.7874 -0.4064)
			(stroke
				(width 0.1524)
				(type default)
			)
			(layer "F.SilkS")
		)
		(fp_line
			(start 0.67945 0.3048)
			(end 0.120396 0.3048)
			(stroke
				(width 0.1)
				(type default)
			)
			(layer "F.Fab")
		)
		(fp_line
			(start 0.67945 -0.3048)
			(end 0.67945 0.3048)
			(stroke
				(width 0.1)
				(type default)
			)
			(layer "F.Fab")
		)
		(fp_line
			(start 0.12065 -0.2794)
			(end 0.12065 -0.3048)
			(stroke
				(width 0.1)
				(type default)
			)
			(layer "F.Fab")
		)
		(fp_line
			(start 0.12065 -0.3048)
			(end 0.67945 -0.3048)
			(stroke
				(width 0.1)
				(type default)
			)
			(layer "F.Fab")
		)
		(fp_line
			(start 0.120396 0.3048)
			(end 0.120396 0.2794)
			(stroke
				(width 0.1)
				(type default)
			)
			(layer "F.Fab")
		)
		(fp_line
			(start 0.120396 0.2794)
			(end -0.12065 0.2794)
			(stroke
				(width 0.1)
				(type default)
			)
			(layer "F.Fab")
		)
		(fp_line
			(start -0.12065 0.3048)
			(end -0.67945 0.3048)
			(stroke
				(width 0.1)
				(type default)
			)
			(layer "F.Fab")
		)
		(fp_line
			(start -0.12065 0.2794)
			(end -0.12065 0.3048)
			(stroke
				(width 0.1)
				(type default)
			)
			(layer "F.Fab")
		)
		(fp_line
			(start -0.12065 -0.2794)
			(end 0.12065 -0.2794)
			(stroke
				(width 0.1)
				(type default)
			)
			(layer "F.Fab")
		)
		(fp_line
			(start -0.12065 -0.305054)
			(end -0.12065 -0.2794)
			(stroke
				(width 0.1)
				(type default)
			)
			(layer "F.Fab")
		)
		(fp_line
			(start -0.67945 0.3048)
			(end -0.67945 -0.305054)
			(stroke
				(width 0.1)
				(type default)
			)
			(layer "F.Fab")
		)
		(fp_line
			(start -0.67945 -0.305054)
			(end -0.12065 -0.305054)
			(stroke
				(width 0.1)
				(type default)
			)
			(layer "F.Fab")
		)
		(pad "1" smd circle
			(at -0.40005 0 180)
			(size 0 0)
			(layers "F.Cu" "F.Mask" "F.Paste")
			(net "SMB_BIC_I2C6_MUX_SSD_0_7_ADC_R_SDA")
		)
		(pad "2" smd circle
			(at 0.40005 0 180)
			(size 0 0)
			(layers "F.Cu" "F.Mask" "F.Paste")
			(net "SMB_SSD6_ADC_SDA")
		)
	)
	(footprint ""
		(layer "F.Cu")
		(at 82.661506 -131.686808 180)
		(property "Reference" "C22"
			(at 0 0 180)
			(layer "F.SilkS")
			(hide yes)
			(effects
				(font
					(size 1.27 1.27)
				)
			)
		)
		(property "Value" ""
			(at 0 0 180)
			(layer "F.Fab")
			(effects
				(font
					(size 1.27 1.27)
				)
			)
		)
		(duplicate_pad_numbers_are_jumpers no)
		(fp_line
			(start 0.299974 0.150114)
			(end -0.299974 0.150114)
			(stroke
				(width 0.1)
				(type default)
			)
			(layer "F.Fab")
		)
		(fp_line
			(start 0.299974 -0.150114)
			(end 0.299974 0.150114)
			(stroke
				(width 0.1)
				(type default)
			)
			(layer "F.Fab")
		)
		(fp_line
			(start -0.299974 0.150114)
			(end -0.299974 -0.150114)
			(stroke
				(width 0.1)
				(type default)
			)
			(layer "F.Fab")
		)
		(fp_line
			(start -0.299974 -0.150114)
			(end 0.299974 -0.150114)
			(stroke
				(width 0.1)
				(type default)
			)
			(layer "F.Fab")
		)
		(pad "1" smd rect
			(at -0.2667 0 180)
			(size 0.3048 0.381)
			(layers "F.Cu" "F.Mask" "F.Paste")
			(net "P5E_PEX0_STN0_TX_DN<5>")
		)
		(pad "2" smd rect
			(at 0.2667 0 180)
			(size 0.3048 0.381)
			(layers "F.Cu" "F.Mask" "F.Paste")
			(net "P5E_PEX0_STN0_TX_C_DN<5>")
		)
	)
)
